(kicad_pcb
	(version 20260206)
	(generator "pcbnew")
	(generator_version "10.0")
	(general
		(thickness 1.6)
		(legacy_teardrops no)
	)
	(paper "A4")
	(title_block
		(title "Wiwynn_Tioga_Pass_MB.brd")
		(comment 1 "Tioga Pass / footprints 2043-2049 of 4770")
	)
	(layers
		(0 "F.Cu" signal "TOP")
		(4 "In1.Cu" signal "L2GND")
		(6 "In2.Cu" signal "L3")
		(8 "In3.Cu" signal "L4GND")
		(10 "In4.Cu" signal "L5")
		(12 "In5.Cu" signal "L6GND")
		(14 "In6.Cu" signal "L7VCC")
		(16 "In7.Cu" signal "L8VCC")
		(18 "In8.Cu" signal "L9GND")
		(20 "In9.Cu" signal "L10")
		(22 "In10.Cu" signal "L11GND")
		(24 "In11.Cu" signal "L12")
		(26 "In12.Cu" signal "L13GND")
		(2 "B.Cu" signal "BOTTOM")
		(9 "F.Adhes" user "F.Adhesive")
		(11 "B.Adhes" user "B.Adhesive")
		(13 "F.Paste" user "Package Geometry/Pastemask Top")
		(15 "B.Paste" user "Package Geometry/Pastemask Bottom")
		(5 "F.SilkS" user "Ref Des/Silkscreen Top")
		(7 "B.SilkS" user "Ref Des/Silkscreen Bottom")
		(1 "F.Mask" user "Board Geometry/Soldermask Top")
		(3 "B.Mask" user "Board Geometry/Soldermask Bottom")
		(17 "Dwgs.User" user "User.Drawings")
		(19 "Cmts.User" user "User.Comments")
		(21 "Eco1.User" user "User.Eco1")
		(23 "Eco2.User" user "User.Eco2")
		(25 "Edge.Cuts" user "Board Geometry/Outline")
		(27 "Margin" user)
		(31 "F.CrtYd" user "Package Geometry/Place Bound Top")
		(29 "B.CrtYd" user "Package Geometry/Place Bound Bottom")
		(35 "F.Fab" user "Ref Des/Assembly Top")
		(33 "B.Fab" user "Ref Des/Assembly Bottom")
	)
	(footprint ""
		(layer "F.Cu")
		(at 27.423364 -73.744328 90)
		(property "Reference" "RT11"
			(at 1.01473 0.656336 0)
			(unlocked yes)
			(layer "F.SilkS")
			(effects
				(font
					(size 0.4064 0.254)
					(thickness 0.1524)
				)
			)
		)
		(property "Value" ""
			(at 0 0 90)
			(layer "F.Fab")
			(effects
				(font
					(size 1.27 1.27)
				)
			)
		)
		(duplicate_pad_numbers_are_jumpers no)
		(fp_poly
			(pts
				(xy -0.4953 -0.2032) (xy 0.4953 -0.2032) (xy 0.4953 1.6002) (xy -0.4953 1.6002)
			)
			(stroke
				(width 0)
				(type default)
			)
			(fill no)
			(layer "F.CrtYd")
		)
		(fp_line
			(start 0.4953 -0.2032)
			(end 0.4953 1.6002)
			(stroke
				(width 0.1)
				(type default)
			)
			(layer "F.Fab")
		)
		(fp_line
			(start -0.4953 -0.2032)
			(end 0.4953 -0.2032)
			(stroke
				(width 0.1)
				(type default)
			)
			(layer "F.Fab")
		)
		(fp_line
			(start 0.4953 1.6002)
			(end -0.4953 1.6002)
			(stroke
				(width 0.1)
				(type default)
			)
			(layer "F.Fab")
		)
		(fp_line
			(start -0.4953 1.6002)
			(end -0.4953 -0.2032)
			(stroke
				(width 0.1)
				(type default)
			)
			(layer "F.Fab")
		)
		(pad "1" smd rect
			(at 0 0 90)
			(size 0.762 0.889)
			(layers "F.Cu" "F.Mask" "F.Paste")
			(net "VR_PVCCIN_CPU1_PH3_BOOT")
		)
		(pad "2" smd rect
			(at 0 1.397 90)
			(size 0.762 0.889)
			(layers "F.Cu" "F.Mask" "F.Paste")
			(net "VR_PVCCIN_CPU1_PH3_BOOT_R")
		)
		(zone
			(layer "F.Cu")
			(hatch none 0.5)
			(connect_pads
				(clearance 0)
			)
			(min_thickness 0.25)
			(keepout
				(tracks allowed)
				(vias not_allowed)
				(pads allowed)
				(copperpour not_allowed)
				(footprints allowed)
			)
			(placement
				(enabled no)
				(sheetname "")
			)
			(fill
				(thermal_gap 0.5)
				(thermal_bridge_width 0.5)
				(island_removal_mode 0)
			)
			(polygon
				(pts
					(xy 28.375864 -74.125328) (xy 27.867864 -74.125328) (xy 27.867864 -73.363328) (xy 28.375864 -73.363328)
				)
			)
		)
		(zone
			(layer "F.Cu")
			(hatch none 0.5)
			(connect_pads
				(clearance 0)
			)
			(min_thickness 0.25)
			(keepout
				(tracks not_allowed)
				(vias allowed)
				(pads allowed)
				(copperpour not_allowed)
				(footprints allowed)
			)
			(placement
				(enabled no)
				(sheetname "")
			)
			(fill
				(thermal_gap 0.5)
				(thermal_bridge_width 0.5)
				(island_removal_mode 0)
			)
			(polygon
				(pts
					(xy 28.375864 -73.363328) (xy 28.375864 -74.125328) (xy 27.867864 -74.125328) (xy 27.867864 -73.363328)
				)
			)
		)
	)
	(footprint ""
		(layer "F.Cu")
		(at 466.217 -0.2032 90)
		(property "Reference" "C9G22"
			(at 0 0 90)
			(layer "F.SilkS")
			(hide yes)
			(effects
				(font
					(size 1.27 1.27)
				)
			)
		)
		(property "Value" ""
			(at 0 0 90)
			(layer "F.Fab")
			(effects
				(font
					(size 1.27 1.27)
				)
			)
		)
		(duplicate_pad_numbers_are_jumpers no)
		(fp_poly
			(pts
				(xy 0.3048 -0.1016) (xy 0.3048 0.9906) (xy -0.3048 0.9906) (xy -0.3048 -0.1016)
			)
			(stroke
				(width 0)
				(type default)
			)
			(fill no)
			(layer "F.CrtYd")
		)
		(fp_line
			(start 0.3048 -0.1016)
			(end -0.3048 -0.1016)
			(stroke
				(width 0.1)
				(type default)
			)
			(layer "F.Fab")
		)
		(fp_line
			(start -0.3048 -0.1016)
			(end -0.3048 0.9906)
			(stroke
				(width 0.1)
				(type default)
			)
			(layer "F.Fab")
		)
		(fp_line
			(start 0.3048 0.9906)
			(end 0.3048 -0.1016)
			(stroke
				(width 0.1)
				(type default)
			)
			(layer "F.Fab")
		)
		(fp_line
			(start -0.3048 0.9906)
			(end 0.3048 0.9906)
			(stroke
				(width 0.1)
				(type default)
			)
			(layer "F.Fab")
		)
		(pad "1" smd rect
			(at 0 0 90)
			(size 0.508 0.508)
			(layers "F.Cu" "F.Mask" "F.Paste")
			(net "A_P3V_BAT_SCALED")
		)
		(pad "2" smd rect
			(at 0 0.889 90)
			(size 0.508 0.508)
			(layers "F.Cu" "F.Mask" "F.Paste")
			(net "GND")
		)
		(zone
			(layer "F.Cu")
			(hatch none 0.5)
			(connect_pads
				(clearance 0)
			)
			(min_thickness 0.25)
			(keepout
				(tracks allowed)
				(vias not_allowed)
				(pads allowed)
				(copperpour not_allowed)
				(footprints allowed)
			)
			(placement
				(enabled no)
				(sheetname "")
			)
			(fill
				(thermal_gap 0.5)
				(thermal_bridge_width 0.5)
				(island_removal_mode 0)
			)
			(polygon
				(pts
					(xy 466.471 0.0508) (xy 466.471 -0.4572) (xy 466.852 -0.4572) (xy 466.852 0.0508)
				)
			)
		)
		(zone
			(layer "F.Cu")
			(hatch none 0.5)
			(connect_pads
				(clearance 0)
			)
			(min_thickness 0.25)
			(keepout
				(tracks not_allowed)
				(vias allowed)
				(pads allowed)
				(copperpour not_allowed)
				(footprints allowed)
			)
			(placement
				(enabled no)
				(sheetname "")
			)
			(fill
				(thermal_gap 0.5)
				(thermal_bridge_width 0.5)
				(island_removal_mode 0)
			)
			(polygon
				(pts
					(xy 466.852 0.0508) (xy 466.852 -0.4572) (xy 466.471 -0.4572) (xy 466.471 0.0508)
				)
			)
		)
	)
	(footprint ""
		(layer "F.Cu")
		(at 87.158068 -12.954 -90)
		(property "Reference" "C2G3"
			(at 1.848866 0.752348 270)
			(unlocked yes)
			(layer "F.SilkS")
			(effects
				(font
					(size 1.27 0.9652)
					(thickness 0.1524)
				)
			)
		)
		(property "Value" ""
			(at 0 0 270)
			(layer "F.Fab")
			(effects
				(font
					(size 1.27 1.27)
				)
			)
		)
		(duplicate_pad_numbers_are_jumpers no)
		(fp_rect
			(start -0.500126 1.598422)
			(end 0.500126 -0.201422)
			(stroke
				(width 0)
				(type default)
			)
			(fill no)
			(layer "F.CrtYd")
		)
		(fp_line
			(start -0.500126 1.598422)
			(end -0.500126 -0.201422)
			(stroke
				(width 0.1)
				(type default)
			)
			(layer "F.Fab")
		)
		(fp_line
			(start 0.500126 1.598422)
			(end -0.500126 1.598422)
			(stroke
				(width 0.1)
				(type default)
			)
			(layer "F.Fab")
		)
		(fp_line
			(start -0.500126 -0.201422)
			(end 0.500126 -0.201422)
			(stroke
				(width 0.1)
				(type default)
			)
			(layer "F.Fab")
		)
		(fp_line
			(start 0.500126 -0.201422)
			(end 0.500126 1.598422)
			(stroke
				(width 0.1)
				(type default)
			)
			(layer "F.Fab")
		)
		(pad "1" smd rect
			(at 0 0 180)
			(size 0.889 0.9906)
			(layers "F.Cu" "F.Mask" "F.Paste")
			(net "PVDDQ_GHJ")
		)
		(pad "2" smd rect
			(at 0 1.397 180)
			(size 0.889 0.9906)
			(layers "F.Cu" "F.Mask" "F.Paste")
			(net "GND")
		)
		(zone
			(layer "F.Cu")
			(hatch none 0.5)
			(connect_pads
				(clearance 0)
			)
			(min_thickness 0.25)
			(keepout
				(tracks not_allowed)
				(vias allowed)
				(pads allowed)
				(copperpour not_allowed)
				(footprints allowed)
			)
			(placement
				(enabled no)
				(sheetname "")
			)
			(fill
				(thermal_gap 0.5)
				(thermal_bridge_width 0.5)
				(island_removal_mode 0)
			)
			(polygon
				(pts
					(xy 86.205568 -13.4493) (xy 86.205568 -12.4587) (xy 86.713568 -12.4587) (xy 86.713568 -13.4493)
				)
			)
		)
		(zone
			(layer "F.Cu")
			(hatch none 0.5)
			(connect_pads
				(clearance 0)
			)
			(min_thickness 0.25)
			(keepout
				(tracks allowed)
				(vias not_allowed)
				(pads allowed)
				(copperpour not_allowed)
				(footprints allowed)
			)
			(placement
				(enabled no)
				(sheetname "")
			)
			(fill
				(thermal_gap 0.5)
				(thermal_bridge_width 0.5)
				(island_removal_mode 0)
			)
			(polygon
				(pts
					(xy 86.205568 -13.4493) (xy 86.205568 -12.4587) (xy 86.713568 -12.4587) (xy 86.713568 -13.4493)
				)
			)
		)
	)
	(footprint ""
		(layer "F.Cu")
		(at 427.609 -20.955 90)
		(property "Reference" "CR10W2"
			(at 1.06934 -0.39116 0)
			(unlocked yes)
			(layer "F.SilkS")
			(effects
				(font
					(size 0.4064 0.254)
					(thickness 0.1524)
				)
				(justify left)
			)
		)
		(property "Value" ""
			(at 0 0 90)
			(layer "F.Fab")
			(effects
				(font
					(size 1.27 1.27)
				)
			)
		)
		(duplicate_pad_numbers_are_jumpers no)
		(fp_line
			(start 1.103122 1.054354)
			(end 1.103122 2.177796)
			(stroke
				(width 0.1524)
				(type default)
			)
			(layer "F.SilkS")
		)
		(fp_line
			(start 1.583944 2.177796)
			(end 0.6223 2.177796)
			(stroke
				(width 0.1524)
				(type default)
			)
			(layer "F.SilkS")
		)
		(fp_line
			(start 1.103122 2.177796)
			(end 1.583944 3.010662)
			(stroke
				(width 0.1524)
				(type default)
			)
			(layer "F.SilkS")
		)
		(fp_line
			(start 1.583944 3.010662)
			(end 1.103122 3.010662)
			(stroke
				(width 0.1524)
				(type default)
			)
			(layer "F.SilkS")
		)
		(fp_line
			(start 1.103122 3.010662)
			(end 0.6223 3.010662)
			(stroke
				(width 0.1524)
				(type default)
			)
			(layer "F.SilkS")
		)
		(fp_line
			(start 0.6223 3.010662)
			(end 1.103122 2.177796)
			(stroke
				(width 0.1524)
				(type default)
			)
			(layer "F.SilkS")
		)
		(fp_line
			(start 1.103122 3.922268)
			(end 1.103122 3.010662)
			(stroke
				(width 0.1524)
				(type default)
			)
			(layer "F.SilkS")
		)
		(fp_poly
			(pts
				(xy -0.67437 0.24384) (xy -0.67437 2.04216) (xy 0.67437 2.04216) (xy 0.67437 0.24384)
			)
			(stroke
				(width 0)
				(type default)
			)
			(fill no)
			(layer "F.CrtYd")
		)
		(fp_line
			(start 0.67437 0.24384)
			(end -0.67437 0.24384)
			(stroke
				(width 0.1)
				(type default)
			)
			(layer "F.Fab")
		)
		(fp_line
			(start -0.67437 0.24384)
			(end -0.67437 2.04216)
			(stroke
				(width 0.1)
				(type default)
			)
			(layer "F.Fab")
		)
		(fp_line
			(start 0.67437 2.04216)
			(end 0.67437 0.24384)
			(stroke
				(width 0.1)
				(type default)
			)
			(layer "F.Fab")
		)
		(fp_line
			(start -0.67437 2.04216)
			(end 0.67437 2.04216)
			(stroke
				(width 0.1)
				(type default)
			)
			(layer "F.Fab")
		)
		(fp_line
			(start 1.583944 2.177796)
			(end 0.6223 2.177796)
			(stroke
				(width 0.1)
				(type default)
			)
			(layer "F.Fab")
		)
		(fp_line
			(start 1.103122 2.177796)
			(end 1.103122 1.054354)
			(stroke
				(width 0.1)
				(type default)
			)
			(layer "F.Fab")
		)
		(fp_line
			(start 1.103122 2.177796)
			(end 1.583944 3.010662)
			(stroke
				(width 0.1)
				(type default)
			)
			(layer "F.Fab")
		)
		(fp_line
			(start 1.583944 3.010662)
			(end 0.6223 3.010662)
			(stroke
				(width 0.1)
				(type default)
			)
			(layer "F.Fab")
		)
		(fp_line
			(start 1.103122 3.010662)
			(end 1.103122 3.922268)
			(stroke
				(width 0.1)
				(type default)
			)
			(layer "F.Fab")
		)
		(fp_line
			(start 0.6223 3.010662)
			(end 1.103122 2.177796)
			(stroke
				(width 0.1)
				(type default)
			)
			(layer "F.Fab")
		)
		(pad "1" smd rect
			(at 0 0 90)
			(size 0.4064 1.016)
			(layers "F.Cu" "F.Mask" "F.Paste")
			(net "P5V_STBY")
		)
		(pad "2" smd rect
			(at 0 2.286 90)
			(size 0.4064 1.016)
			(layers "F.Cu" "F.Mask" "F.Paste")
			(net "PUMP_PWM_OUT_R")
		)
	)
	(footprint ""
		(layer "F.Cu")
		(at 399.159222 -149.225 180)
		(property "Reference" "R8A6"
			(at 0 0 180)
			(layer "F.SilkS")
			(hide yes)
			(effects
				(font
					(size 1.27 1.27)
				)
			)
		)
		(property "Value" ""
			(at 0 0 180)
			(layer "F.Fab")
			(effects
				(font
					(size 1.27 1.27)
				)
			)
		)
		(duplicate_pad_numbers_are_jumpers no)
		(fp_poly
			(pts
				(xy -0.2794 -0.1016) (xy 0.2794 -0.1016) (xy 0.2794 0.9906) (xy -0.2794 0.9906)
			)
			(stroke
				(width 0)
				(type default)
			)
			(fill no)
			(layer "F.CrtYd")
		)
		(fp_line
			(start 0.2794 0.9906)
			(end 0.2794 -0.1016)
			(stroke
				(width 0.1)
				(type default)
			)
			(layer "F.Fab")
		)
		(fp_line
			(start 0.2794 -0.1016)
			(end -0.2794 -0.1016)
			(stroke
				(width 0.1)
				(type default)
			)
			(layer "F.Fab")
		)
		(fp_line
			(start -0.2794 0.9906)
			(end 0.2794 0.9906)
			(stroke
				(width 0.1)
				(type default)
			)
			(layer "F.Fab")
		)
		(fp_line
			(start -0.2794 -0.1016)
			(end -0.2794 0.9906)
			(stroke
				(width 0.1)
				(type default)
			)
			(layer "F.Fab")
		)
		(pad "1" smd rect
			(at 0 0 180)
			(size 0.508 0.508)
			(layers "F.Cu" "F.Mask" "F.Paste")
			(net "P3V3_STBY")
		)
		(pad "2" smd rect
			(at 0 0.889 180)
			(size 0.508 0.508)
			(layers "F.Cu" "F.Mask" "F.Paste")
			(net "PWRGD_PVNN_PCH_R")
		)
		(zone
			(layer "F.Cu")
			(hatch none 0.5)
			(connect_pads
				(clearance 0)
			)
			(min_thickness 0.25)
			(keepout
				(tracks not_allowed)
				(vias allowed)
				(pads allowed)
				(copperpour not_allowed)
				(footprints allowed)
			)
			(placement
				(enabled no)
				(sheetname "")
			)
			(fill
				(thermal_gap 0.5)
				(thermal_bridge_width 0.5)
				(island_removal_mode 0)
			)
			(polygon
				(pts
					(xy 399.413222 -149.86) (xy 398.905222 -149.86) (xy 398.905222 -149.479) (xy 399.413222 -149.479)
				)
			)
		)
		(zone
			(layer "F.Cu")
			(hatch none 0.5)
			(connect_pads
				(clearance 0)
			)
			(min_thickness 0.25)
			(keepout
				(tracks allowed)
				(vias not_allowed)
				(pads allowed)
				(copperpour not_allowed)
				(footprints allowed)
			)
			(placement
				(enabled no)
				(sheetname "")
			)
			(fill
				(thermal_gap 0.5)
				(thermal_bridge_width 0.5)
				(island_removal_mode 0)
			)
			(polygon
				(pts
					(xy 399.413222 -149.479) (xy 398.905222 -149.479) (xy 398.905222 -149.86) (xy 399.413222 -149.86)
				)
			)
		)
	)
	(footprint ""
		(layer "F.Cu")
		(at 347.1926 -10.2108 -90)
		(property "Reference" "C7G34"
			(at 0 0 270)
			(layer "F.SilkS")
			(hide yes)
			(effects
				(font
					(size 1.27 1.27)
				)
			)
		)
		(property "Value" ""
			(at 0 0 270)
			(layer "F.Fab")
			(effects
				(font
					(size 1.27 1.27)
				)
			)
		)
		(duplicate_pad_numbers_are_jumpers no)
		(fp_rect
			(start -0.3048 -0.1016)
			(end 0.3048 0.9906)
			(stroke
				(width 0)
				(type default)
			)
			(fill no)
			(layer "F.CrtYd")
		)
		(fp_line
			(start -0.3048 0.9906)
			(end 0.3048 0.9906)
			(stroke
				(width 0.1)
				(type default)
			)
			(layer "F.Fab")
		)
		(fp_line
			(start 0.3048 0.9906)
			(end 0.3048 -0.1016)
			(stroke
				(width 0.1)
				(type default)
			)
			(layer "F.Fab")
		)
		(fp_line
			(start -0.3048 -0.1016)
			(end -0.3048 0.9906)
			(stroke
				(width 0.1)
				(type default)
			)
			(layer "F.Fab")
		)
		(fp_line
			(start 0.3048 -0.1016)
			(end -0.3048 -0.1016)
			(stroke
				(width 0.1)
				(type default)
			)
			(layer "F.Fab")
		)
		(pad "1" smd rect
			(at 0 0 270)
			(size 0.508 0.508)
			(layers "F.Cu" "F.Mask" "F.Paste")
			(net "P5V_STBY")
		)
		(pad "2" smd rect
			(at 0 0.889 270)
			(size 0.508 0.508)
			(layers "F.Cu" "F.Mask" "F.Paste")
			(net "GND")
		)
		(zone
			(layer "F.Cu")
			(hatch none 0.5)
			(connect_pads
				(clearance 0)
			)
			(min_thickness 0.25)
			(keepout
				(tracks not_allowed)
				(vias allowed)
				(pads allowed)
				(copperpour not_allowed)
				(footprints allowed)
			)
			(placement
				(enabled no)
				(sheetname "")
			)
			(fill
				(thermal_gap 0.5)
				(thermal_bridge_width 0.5)
				(island_removal_mode 0)
			)
			(polygon
				(pts
					(xy 346.9386 -10.4648) (xy 346.5576 -10.4648) (xy 346.5576 -9.9568) (xy 346.9386 -9.9568)
				)
			)
		)
		(zone
			(layer "F.Cu")
			(hatch none 0.5)
			(connect_pads
				(clearance 0)
			)
			(min_thickness 0.25)
			(keepout
				(tracks allowed)
				(vias not_allowed)
				(pads allowed)
				(copperpour not_allowed)
				(footprints allowed)
			)
			(placement
				(enabled no)
				(sheetname "")
			)
			(fill
				(thermal_gap 0.5)
				(thermal_bridge_width 0.5)
				(island_removal_mode 0)
			)
			(polygon
				(pts
					(xy 346.9386 -10.4648) (xy 346.5576 -10.4648) (xy 346.5576 -9.9568) (xy 346.9386 -9.9568)
				)
			)
		)
	)
	(footprint ""
		(layer "F.Cu")
		(at 175.387 -83.947 90)
		(property "Reference" "R4D12"
			(at 0 0 90)
			(layer "F.SilkS")
			(hide yes)
			(effects
				(font
					(size 1.27 1.27)
				)
			)
		)
		(property "Value" ""
			(at 0 0 90)
			(layer "F.Fab")
			(effects
				(font
					(size 1.27 1.27)
				)
			)
		)
		(duplicate_pad_numbers_are_jumpers no)
		(fp_poly
			(pts
				(xy -0.2794 -0.1016) (xy 0.2794 -0.1016) (xy 0.2794 0.9906) (xy -0.2794 0.9906)
			)
			(stroke
				(width 0)
				(type default)
			)
			(fill no)
			(layer "F.CrtYd")
		)
		(fp_line
			(start 0.2794 -0.1016)
			(end -0.2794 -0.1016)
			(stroke
				(width 0.1)
				(type default)
			)
			(layer "F.Fab")
		)
		(fp_line
			(start -0.2794 -0.1016)
			(end -0.2794 0.9906)
			(stroke
				(width 0.1)
				(type default)
			)
			(layer "F.Fab")
		)
		(fp_line
			(start 0.2794 0.9906)
			(end 0.2794 -0.1016)
			(stroke
				(width 0.1)
				(type default)
			)
			(layer "F.Fab")
		)
		(fp_line
			(start -0.2794 0.9906)
			(end 0.2794 0.9906)
			(stroke
				(width 0.1)
				(type default)
			)
			(layer "F.Fab")
		)
		(pad "1" smd rect
			(at 0 0 90)
			(size 0.508 0.508)
			(layers "F.Cu" "F.Mask" "F.Paste")
			(net "CLK_100M_CPU0_PE_REFCLK_R_DP")
		)
		(pad "2" smd rect
			(at 0 0.889 90)
			(size 0.508 0.508)
			(layers "F.Cu" "F.Mask" "F.Paste")
			(net "CLK_100M_CPU0_PE_REFCLK_DP")
		)
		(zone
			(layer "F.Cu")
			(hatch none 0.5)
			(connect_pads
				(clearance 0)
			)
			(min_thickness 0.25)
			(keepout
				(tracks allowed)
				(vias not_allowed)
				(pads allowed)
				(copperpour not_allowed)
				(footprints allowed)
			)
			(placement
				(enabled no)
				(sheetname "")
			)
			(fill
				(thermal_gap 0.5)
				(thermal_bridge_width 0.5)
				(island_removal_mode 0)
			)
			(polygon
				(pts
					(xy 175.641 -83.693) (xy 175.641 -84.201) (xy 176.022 -84.201) (xy 176.022 -83.693)
				)
			)
		)
		(zone
			(layer "F.Cu")
			(hatch none 0.5)
			(connect_pads
				(clearance 0)
			)
			(min_thickness 0.25)
			(keepout
				(tracks not_allowed)
				(vias allowed)
				(pads allowed)
				(copperpour not_allowed)
				(footprints allowed)
			)
			(placement
				(enabled no)
				(sheetname "")
			)
			(fill
				(thermal_gap 0.5)
				(thermal_bridge_width 0.5)
				(island_removal_mode 0)
			)
			(polygon
				(pts
					(xy 176.022 -83.693) (xy 176.022 -84.201) (xy 175.641 -84.201) (xy 175.641 -83.693)
				)
			)
		)
	)
)
